#ISCELL
  mstr_misc dns *
  *
#ISCELL
  mstr_symbols intel_corp_bpage *
  *
#ISCELL
  mstr_standard offpage *
  page202_i1
#ISCELL
  mstr_standard offpage *
  page202_i10
#CELL
  mstr_discrete res *
  page202_i101
#CELL
  mstr_discrete res *
  page202_i102
#CELL
  mstr_discrete res *
  page202_i107
#CELL
  mstr_discrete res *
  page202_i108
#CELL
  w_hdl ind-120nh-30-gp *
  page202_i109
#ISCELL
  mstr_standard offpage *
  page202_i11
#CELL
  w_hdl ind-120nh-30-gp *
  page202_i110
#CELL
  w_hdl sc1u10v2kx-4-gp *
  page202_i111
#CELL
  w_hdl sc1u10v2kx-4-gp *
  page202_i112
#CELL
  w_hdl 1r3f-gp *
  page202_i114
#CELL
  w_hdl 1r3f-gp *
  page202_i115
#ISCELL
  mstr_standard offpage *
  page202_i12
#ISCELL
  mstr_symbols gnd *
  page202_i13
#CELL
  mstr_discrete cap *
  page202_i18
#ISCELL
  mstr_standard offpage *
  page202_i2
#CELL
  mstr_discrete cap *
  page202_i22
#CELL
  mstr_discrete cap *
  page202_i24
#ISCELL
  mstr_symbols pvccin_cpu0 *
  page202_i26
#CELL
  dev_discrete cap_a *
  page202_i27
#ISCELL
  mstr_symbols gnd *
  page202_i28
#ISCELL
  mstr_standard offpage *
  page202_i3
#ISCELL
  mstr_symbols gnd *
  page202_i30
#CELL
  mstr_discrete cap *
  page202_i32
#CELL
  mstr_discrete cap *
  page202_i34
#CELL
  dev_discrete cap_a *
  page202_i35
#CELL
  mstr_discrete cap *
  page202_i36
#CELL
  mstr_discrete cap *
  page202_i37
#CELL
  mstr_discrete cap *
  page202_i38
#ISCELL
  mstr_symbols pvccin_cpu0 *
  page202_i4
#ISCELL
  mstr_standard offpage *
  page202_i40
#ISCELL
  mstr_symbols vcc_core *
  page202_i41
#CELL
  mstr_discrete cap *
  page202_i42
#ISCELL
  mstr_symbols gnd *
  page202_i43
#ISCELL
  mstr_symbols vcc_core *
  page202_i44
#CELL
  mstr_discrete cap *
  page202_i45
#CELL
  dev_discrete cap_a *
  page202_i46
#CELL
  mstr_discrete cap *
  page202_i47
#CELL
  mstr_discrete cap *
  page202_i48
#CELL
  mstr_discrete cap *
  page202_i49
#ISCELL
  mstr_standard offpage *
  page202_i50
#CELL
  mstr_discrete cap *
  page202_i51
#ISCELL
  mstr_symbols gnd *
  page202_i52
#ISCELL
  mstr_symbols p5v_stby *
  page202_i59
#ISCELL
  mstr_symbols p5v_stby *
  page202_i60
#CELL
  dev_discrete cap_a *
  page202_i61
#CELL
  dev_discrete cap_a *
  page202_i62
#CELL
  mstr_discrete ir354xx *
  page202_i63
#CELL
  mstr_discrete ir354xx *
  page202_i64
#CELL
  mstr_discrete res *
  page202_i65
#ISCELL
  mstr_symbols gnd *
  page202_i66
#CELL
  mstr_discrete res *
  page202_i67
#ISCELL
  mstr_symbols gnd *
  page202_i68
#CELL
  dev_discrete cap_a *
  page202_i70
#ISCELL
  mstr_symbols gnd *
  page202_i71
#ISCELL
  mstr_symbols gnd *
  page202_i73
#ISCELL
  mstr_symbols gnd *
  page202_i77
#CELL
  mstr_discrete cap *
  page202_i78
#ISCELL
  mstr_symbols gnd *
  page202_i8
#ISCELL
  mstr_symbols gnd *
  page202_i80
#CELL
  dev_discrete cap_a *
  page202_i81
#ISCELL
  mstr_symbols gnd *
  page202_i84
#ISCELL
  mstr_symbols gnd *
  page202_i86
#CELL
  mstr_discrete cap *
  page202_i87
#CELL
  dev_discrete cap_a *
  page202_i9
#CELL
  mstr_discrete cap *
  page202_i97
#CELL
  mstr_discrete cap *
  page202_i98
